FILE_TYPE = MACRO_DRAWING;
SET COLOR_WIRE YELLOW;
SET COLOR_PROP ORANGE;
SET COLOR_DOT WHITE;
SET COLOR_ARC YELLOW;
SET COLOR_BODY GREEN;
SET COLOR_NOTE PURPLE;
SET PROP_DISPLAY VALUE;
SET PAGE_NUMBER P528;
FORCEADD SHEET_A1..1
(750 -650);
FORCEPROP 1 LAST TITLE FPGA<>SMA CONN MAPPING 
J 0
(-1850 250);
DISPLAY 2.468085 (-1850 250);
FORCEPROP 2 LAST CUSTOM_TXT_CDS <XR_PAGE_TITLE>
J 0
(-14820 10700);
DISPLAY 0.638298 (-14820 10700);
PAINT PINK (-14820 10700);
FORCEPROP 1 LAST CUSTOM_TXT_CDS <DOCNO>
J 0
(-1300 -265);
DISPLAY 0.978723 (-1300 -265);
FORCEPROP 1 LAST CUSTOM_TXT_CDS <CON_PAGE_NUM>
J 0
(-1405 -600);
DISPLAY 0.978723 (-1405 -600);
FORCEPROP 1 LAST CUSTOM_TXT_CDS <DATE>
J 0
(50 -475);
DISPLAY 0.978723 (50 -475);
FORCEPROP 1 LAST CUSTOM_TXT_CDS <TITLE>
J 1
(-1035 -20);
DISPLAY 0.978723 (-1035 -20);
FORCEPROP 1 LAST CUSTOM_TXT_CDS <DESIGNER>
J 0
(50 -50);
DISPLAY 0.978723 (50 -50);
FORCEPROP 1 LAST CUSTOM_TXT_CDS <CON_TOTAL_PAGES>
J 0
(-1095 -600);
DISPLAY 0.808511 (-1095 -600);
FORCEPROP 1 LAST CUSTOM_TXT_CDS <ASSY_PN>
J 0
(-1300 -475);
DISPLAY 0.978723 (-1300 -475);
FORCEPROP 1 LAST CUSTOM_TXT_CDS <DOCREV>
J 0
(50 -275);
DISPLAY 0.978723 (50 -275);
FORCEPROP 1 LAST COMMENT_BODY TRUE
J 0
(760 -595);
DISPLAY 0.808511 (760 -595);
DISPLAY INVISIBLE (760 -595);
FORCEPROP 2 LAST PAGE_BORDER TRUE
J 0
(-14820 10700);
DISPLAY 0.638298 (-14820 10700);
PAINT PINK (-14820 10700);
DISPLAY INVISIBLE (-14820 10700);
FORCEPROP 1 LAST CDS_LMAN_SYM_OUTLINE -15850,11500,200,-200
J 0
(750 -650);
DISPLAY 0.468085 (750 -650);
PAINT GREEN (750 -650);
DISPLAY INVISIBLE (750 -650);
FORCEPROP 2 LAST CDS_LIB cls
J 0
(750 -650);
DISPLAY INVISIBLE (750 -650);
FORCEPROP 2 LAST CDS_XR_PAGE_TITLE CR-8 : @TIMECARD_LIB.TIMECARD(SCH_1):PAGE8
J 0
(-14820 10700);
DISPLAY 0.638298 (-14820 10700);
PAINT PINK (-14820 10700);
DISPLAY INVISIBLE (-14820 10700);
FORCENOTE
FPGA<>SMA CONN MAPPING
(-9500 9100) 0;
DISPLAY LEFT (-9500 9100);
DISPLAY 4.914894 (-9500 9100);
FORCENOTE
$CDS_IMAGE|clipboard_0_9.jpg|11750|3681
(-6950 5700) 0;
DISPLAY LEFT (-6950 5700);
QUIT
